(kicad_pcb
	(version 20260206)
	(generator "pcbnew")
	(generator_version "10.0")
	(general
		(thickness 1.6)
		(legacy_teardrops no)
	)
	(paper "A4")
	(title_block
		(title "Bryce Canyon_IOM_IOC_16318-2_OCP.brd")
		(comment 1 "Bryce Canyon / footprint 360 of 1605 (CN1), pads 1-74 of 202")
	)
	(layers
		(0 "F.Cu" signal "TOP")
		(4 "In1.Cu" signal "L2GND")
		(6 "In2.Cu" signal "L3")
		(8 "In3.Cu" signal "L4VCC")
		(10 "In4.Cu" signal "L5VCC")
		(12 "In5.Cu" signal "L6")
		(14 "In6.Cu" signal "L7GND")
		(2 "B.Cu" signal "BOTTOM")
		(9 "F.Adhes" user "F.Adhesive")
		(11 "B.Adhes" user "B.Adhesive")
		(13 "F.Paste" user "Package Geometry/Pastemask Top")
		(15 "B.Paste" user "Package Geometry/Pastemask Bottom")
		(5 "F.SilkS" user "Ref Des/Silkscreen Top")
		(7 "B.SilkS" user "Ref Des/Silkscreen Bottom")
		(1 "F.Mask" user "Board Geometry/Soldermask Top")
		(3 "B.Mask" user "Board Geometry/Soldermask Bottom")
		(17 "Dwgs.User" user "User.Drawings")
		(19 "Cmts.User" user "User.Comments")
		(21 "Eco1.User" user "User.Eco1")
		(23 "Eco2.User" user "User.Eco2")
		(25 "Edge.Cuts" user "Board Geometry/Outline")
		(27 "Margin" user)
		(31 "F.CrtYd" user "Package Geometry/Place Bound Top")
		(29 "B.CrtYd" user "Package Geometry/Place Bound Bottom")
		(35 "F.Fab" user "Ref Des/Assembly Top")
		(33 "B.Fab" user "Ref Des/Assembly Bottom")
	)
	(footprint ""
		(layer "F.Cu")
		(at 141.299946 -44.200064 180)
		(property "Reference" "CN1"
			(at 0 0 180)
			(layer "F.SilkS")
			(hide yes)
			(effects
				(font
					(size 1.27 1.27)
				)
			)
		)
		(property "Value" "AMP-CONN200-13R-4-GP"
			(at 30.332934 43.515534 180)
			(unlocked yes)
			(layer "F.Fab")
			(hide yes)
			(effects
				(font
					(size 1.016 1.016)
					(thickness 0.1524)
				)
			)
		)
		(property "Device Type" "PREFIT-200P-360520-1H542"
			(at 30.332934 41.991534 180)
			(unlocked yes)
			(layer "F.Fab")
			(hide yes)
			(effects
				(font
					(size 1.016 1.016)
					(thickness 0.1524)
				)
			)
		)
		(duplicate_pad_numbers_are_jumpers no)
		(pad "" np_thru_hole circle
			(at 17.135094 -9.344914 180)
			(size 0.254 0.254)
			(drill 2.4638)
			(layers "*.Cu" "*.Mask")
			(clearance 1.4605)
			(thermal_gap 1.4605)
		)
		(pad "" np_thru_hole circle
			(at 17.135094 -2.355088 180)
			(size 0.254 0.254)
			(drill 2.3876)
			(layers "*.Cu" "*.Mask")
			(clearance 1.4224)
			(thermal_gap 1.4224)
		)
		(pad "A1" thru_hole circle
			(at 0 0 180)
			(size 0.762 0.762)
			(drill 0.359918)
			(layers "*.Cu" "*.Mask")
			(remove_unused_layers no)
			(net "PCIE_COMP_TO_IOM_CLK_2_DN")
			(clearance 0.1651)
			(thermal_gap 0.1651)
		)
		(pad "A2" thru_hole circle
			(at 1.800098 1.199896 180)
			(size 0.762 0.762)
			(drill 0.359918)
			(layers "*.Cu" "*.Mask")
			(remove_unused_layers no)
			(net "I2C_DPB_MISC_SDA")
			(clearance 0.1651)
			(thermal_gap 0.1651)
		)
		(pad "A3" thru_hole circle
			(at 3.599942 0 180)
			(size 0.762 0.762)
			(drill 0.359918)
			(layers "*.Cu" "*.Mask")
			(remove_unused_layers no)
			(net "BMC_LOC_HEARTBEAT")
			(clearance 0.1651)
			(thermal_gap 0.1651)
		)
		(pad "A4" thru_hole circle
			(at 5.40004 1.199896 180)
			(size 0.762 0.762)
			(drill 0.359918)
			(layers "*.Cu" "*.Mask")
			(remove_unused_layers no)
			(net "SCC_RMT_FULL_PWR_EN")
			(clearance 0.1651)
			(thermal_gap 0.1651)
		)
		(pad "A5" thru_hole circle
			(at 7.199884 0 180)
			(size 0.762 0.762)
			(drill 0.359918)
			(layers "*.Cu" "*.Mask")
			(remove_unused_layers no)
			(net "PCIE_COMP_TO_IOM_CLK_3_DN")
			(clearance 0.1651)
			(thermal_gap 0.1651)
		)
		(pad "A6" thru_hole circle
			(at 8.999982 1.199896 180)
			(size 0.762 0.762)
			(drill 0.359918)
			(layers "*.Cu" "*.Mask")
			(remove_unused_layers no)
			(net "I2C_EXP_LOC_SDA")
			(clearance 0.1651)
			(thermal_gap 0.1651)
		)
		(pad "A7" thru_hole circle
			(at 10.80008 0 180)
			(size 0.762 0.762)
			(drill 0.359918)
			(layers "*.Cu" "*.Mask")
			(remove_unused_layers no)
			(net "P12V_IOM")
			(clearance 0.1651)
			(thermal_gap 0.1651)
		)
		(pad "A8" thru_hole circle
			(at 12.599924 1.199896 180)
			(size 0.762 0.762)
			(drill 0.359918)
			(layers "*.Cu" "*.Mask")
			(remove_unused_layers no)
			(net "P12V_IOM")
			(clearance 0.1651)
			(thermal_gap 0.1651)
		)
		(pad "A9" thru_hole circle
			(at 21.599906 0 180)
			(size 0.762 0.762)
			(drill 0.359918)
			(layers "*.Cu" "*.Mask")
			(remove_unused_layers no)
			(net "PCIE_COMP_TO_IOM_CLK_4_DN")
			(clearance 0.1651)
			(thermal_gap 0.1651)
		)
		(pad "A10" thru_hole circle
			(at 23.400004 1.199896 180)
			(size 0.762 0.762)
			(drill 0.359918)
			(layers "*.Cu" "*.Mask")
			(remove_unused_layers no)
			(net "SLOTID_1")
			(clearance 0.1651)
			(thermal_gap 0.1651)
		)
		(pad "A11" thru_hole circle
			(at 25.200102 0 180)
			(size 0.762 0.762)
			(drill 0.359918)
			(layers "*.Cu" "*.Mask")
			(remove_unused_layers no)
			(net "BMC_TO_EXP_RESET_N")
			(clearance 0.1651)
			(thermal_gap 0.1651)
		)
		(pad "A12" thru_hole circle
			(at 26.999946 1.199896 180)
			(size 0.762 0.762)
			(drill 0.359918)
			(layers "*.Cu" "*.Mask")
			(remove_unused_layers no)
			(net "USB_COMP_DN")
			(clearance 0.1651)
			(thermal_gap 0.1651)
		)
		(pad "A13" thru_hole circle
			(at 28.800044 0 180)
			(size 0.762 0.762)
			(drill 0.359918)
			(layers "*.Cu" "*.Mask")
			(remove_unused_layers no)
			(net "COMP_TO_BMC_RESET")
			(clearance 0.1651)
			(thermal_gap 0.1651)
		)
		(pad "A14" thru_hole circle
			(at 30.599888 1.199896 180)
			(size 0.762 0.762)
			(drill 0.359918)
			(layers "*.Cu" "*.Mask")
			(remove_unused_layers no)
			(net "I2C_DPB_SDA")
			(clearance 0.1651)
			(thermal_gap 0.1651)
		)
		(pad "A15" thru_hole circle
			(at 32.399986 0 180)
			(size 0.762 0.762)
			(drill 0.359918)
			(layers "*.Cu" "*.Mask")
			(remove_unused_layers no)
			(net "EXP_SPARE_1")
			(clearance 0.1651)
			(thermal_gap 0.1651)
		)
		(pad "A16" thru_hole circle
			(at 34.200084 1.199896 180)
			(size 0.762 0.762)
			(drill 0.359918)
			(layers "*.Cu" "*.Mask")
			(remove_unused_layers no)
			(net "COMP_SPARE_1")
			(clearance 0.1651)
			(thermal_gap 0.1651)
		)
		(pad "B1" thru_hole circle
			(at 0 -1.400048 180)
			(size 0.762 0.762)
			(drill 0.359918)
			(layers "*.Cu" "*.Mask")
			(remove_unused_layers no)
			(net "PCIE_COMP_TO_IOM_CLK_2_DP")
			(clearance 0.1651)
			(thermal_gap 0.1651)
		)
		(pad "B2" thru_hole circle
			(at 1.800098 -0.199898 180)
			(size 0.762 0.762)
			(drill 0.359918)
			(layers "*.Cu" "*.Mask")
			(remove_unused_layers no)
			(net "I2C_DPB_MISC_SCL")
			(clearance 0.1651)
			(thermal_gap 0.1651)
		)
		(pad "B3" thru_hole circle
			(at 3.599942 -1.400048 180)
			(size 0.762 0.762)
			(drill 0.359918)
			(layers "*.Cu" "*.Mask")
			(remove_unused_layers no)
			(net "BMC_RMT_HEARTBEAT")
			(clearance 0.1651)
			(thermal_gap 0.1651)
		)
		(pad "B4" thru_hole circle
			(at 5.40004 -0.199898 180)
			(size 0.762 0.762)
			(drill 0.359918)
			(layers "*.Cu" "*.Mask")
			(remove_unused_layers no)
			(net "SCC_LOC_FULL_PWR_EN")
			(clearance 0.1651)
			(thermal_gap 0.1651)
		)
		(pad "B5" thru_hole circle
			(at 7.199884 -1.400048 180)
			(size 0.762 0.762)
			(drill 0.359918)
			(layers "*.Cu" "*.Mask")
			(remove_unused_layers no)
			(net "PCIE_COMP_TO_IOM_CLK_3_DP")
			(clearance 0.1651)
			(thermal_gap 0.1651)
		)
		(pad "B6" thru_hole circle
			(at 8.999982 -0.199898 180)
			(size 0.762 0.762)
			(drill 0.359918)
			(layers "*.Cu" "*.Mask")
			(remove_unused_layers no)
			(net "I2C_EXP_LOC_SCL")
			(clearance 0.1651)
			(thermal_gap 0.1651)
		)
		(pad "B7" thru_hole circle
			(at 10.80008 -1.400048 180)
			(size 0.762 0.762)
			(drill 0.359918)
			(layers "*.Cu" "*.Mask")
			(remove_unused_layers no)
			(net "P12V_A_PGOOD")
			(clearance 0.1651)
			(thermal_gap 0.1651)
		)
		(pad "B8" thru_hole circle
			(at 12.599924 -0.199898 180)
			(size 0.762 0.762)
			(drill 0.359918)
			(layers "*.Cu" "*.Mask")
			(remove_unused_layers no)
			(net "P12V_IOM")
			(clearance 0.1651)
			(thermal_gap 0.1651)
		)
		(pad "B9" thru_hole circle
			(at 21.599906 -1.400048 180)
			(size 0.762 0.762)
			(drill 0.359918)
			(layers "*.Cu" "*.Mask")
			(remove_unused_layers no)
			(net "PCIE_COMP_TO_IOM_CLK_4_DP")
			(clearance 0.1651)
			(thermal_gap 0.1651)
		)
		(pad "B10" thru_hole circle
			(at 23.400004 -0.199898 180)
			(size 0.762 0.762)
			(drill 0.359918)
			(layers "*.Cu" "*.Mask")
			(remove_unused_layers no)
			(net "SLOTID_0")
			(clearance 0.1651)
			(thermal_gap 0.1651)
		)
		(pad "B11" thru_hole circle
			(at 25.200102 -1.400048 180)
			(size 0.762 0.762)
			(drill 0.359918)
			(layers "*.Cu" "*.Mask")
			(remove_unused_layers no)
			(net "DPB_MISC_ALERT")
			(clearance 0.1651)
			(thermal_gap 0.1651)
		)
		(pad "B12" thru_hole circle
			(at 26.999946 -0.199898 180)
			(size 0.762 0.762)
			(drill 0.359918)
			(layers "*.Cu" "*.Mask")
			(remove_unused_layers no)
			(net "USB_COMP_DP")
			(clearance 0.1651)
			(thermal_gap 0.1651)
		)
		(pad "B13" thru_hole circle
			(at 28.800044 -1.400048 180)
			(size 0.762 0.762)
			(drill 0.359918)
			(layers "*.Cu" "*.Mask")
			(remove_unused_layers no)
			(net "SYS_RESET_N")
			(clearance 0.1651)
			(thermal_gap 0.1651)
		)
		(pad "B14" thru_hole circle
			(at 30.599888 -0.199898 180)
			(size 0.762 0.762)
			(drill 0.359918)
			(layers "*.Cu" "*.Mask")
			(remove_unused_layers no)
			(net "I2C_DPB_SCL")
			(clearance 0.1651)
			(thermal_gap 0.1651)
		)
		(pad "B15" thru_hole circle
			(at 32.399986 -1.400048 180)
			(size 0.762 0.762)
			(drill 0.359918)
			(layers "*.Cu" "*.Mask")
			(remove_unused_layers no)
			(net "EXP_SPARE_0")
			(clearance 0.1651)
			(thermal_gap 0.1651)
		)
		(pad "B16" thru_hole circle
			(at 34.200084 -0.199898 180)
			(size 0.762 0.762)
			(drill 0.359918)
			(layers "*.Cu" "*.Mask")
			(remove_unused_layers no)
			(net "COMP_SPARE_0")
			(clearance 0.1651)
			(thermal_gap 0.1651)
		)
		(pad "C1" thru_hole circle
			(at 0 -3.599942 180)
			(size 0.762 0.762)
			(drill 0.359918)
			(layers "*.Cu" "*.Mask")
			(remove_unused_layers no)
			(net "IOM_MATED_N")
			(clearance 0.1651)
			(thermal_gap 0.1651)
		)
		(pad "C2" thru_hole circle
			(at 1.800098 -2.400046 180)
			(size 0.762 0.762)
			(drill 0.359918)
			(layers "*.Cu" "*.Mask")
			(remove_unused_layers no)
			(net "I2C_SCC_SDA")
			(clearance 0.1651)
			(thermal_gap 0.1651)
		)
		(pad "C3" thru_hole circle
			(at 3.599942 -3.599942 180)
			(size 0.762 0.762)
			(drill 0.359918)
			(layers "*.Cu" "*.Mask")
			(remove_unused_layers no)
			(net "SCC_RMT_HEARTBEAT")
			(clearance 0.1651)
			(thermal_gap 0.1651)
		)
		(pad "C4" thru_hole circle
			(at 5.40004 -2.400046 180)
			(size 0.762 0.762)
			(drill 0.359918)
			(layers "*.Cu" "*.Mask")
			(remove_unused_layers no)
			(net "SYS_PWR_LED")
			(clearance 0.1651)
			(thermal_gap 0.1651)
		)
		(pad "C5" thru_hole circle
			(at 7.199884 -3.599942 180)
			(size 0.762 0.762)
			(drill 0.359918)
			(layers "*.Cu" "*.Mask")
			(remove_unused_layers no)
			(net "IOM_LOC_INS_N")
			(clearance 0.1651)
			(thermal_gap 0.1651)
		)
		(pad "C6" thru_hole circle
			(at 8.999982 -2.400046 180)
			(size 0.762 0.762)
			(drill 0.359918)
			(layers "*.Cu" "*.Mask")
			(remove_unused_layers no)
			(net "I2C_EXP_RMT_SDA")
			(clearance 0.1651)
			(thermal_gap 0.1651)
		)
		(pad "C7" thru_hole circle
			(at 10.80008 -3.599942 180)
			(size 0.762 0.762)
			(drill 0.359918)
			(layers "*.Cu" "*.Mask")
			(remove_unused_layers no)
			(net "UART_SDB_RX")
			(clearance 0.1651)
			(thermal_gap 0.1651)
		)
		(pad "C8" thru_hole circle
			(at 12.599924 -2.400046 180)
			(size 0.762 0.762)
			(drill 0.359918)
			(layers "*.Cu" "*.Mask")
			(remove_unused_layers no)
			(net "P12V_IOM")
			(clearance 0.1651)
			(thermal_gap 0.1651)
		)
		(pad "C9" thru_hole circle
			(at 21.599906 -3.599942 180)
			(size 0.762 0.762)
			(drill 0.359918)
			(layers "*.Cu" "*.Mask")
			(remove_unused_layers no)
			(net "I2C_BMC_COMP_ALERT_N")
			(clearance 0.1651)
			(thermal_gap 0.1651)
		)
		(pad "C10" thru_hole circle
			(at 23.400004 -2.400046 180)
			(size 0.762 0.762)
			(drill 0.359918)
			(layers "*.Cu" "*.Mask")
			(remove_unused_layers no)
			(net "I2C_BMC_COMP_SDA")
			(clearance 0.1651)
			(thermal_gap 0.1651)
		)
		(pad "C11" thru_hole circle
			(at 25.200102 -3.599942 180)
			(size 0.762 0.762)
			(drill 0.359918)
			(layers "*.Cu" "*.Mask")
			(remove_unused_layers no)
			(net "UART_COMP_RX")
			(clearance 0.1651)
			(thermal_gap 0.1651)
		)
		(pad "C12" thru_hole circle
			(at 26.999946 -2.400046 180)
			(size 0.762 0.762)
			(drill 0.359918)
			(layers "*.Cu" "*.Mask")
			(remove_unused_layers no)
			(net "COMP_PWR_EN")
			(clearance 0.1651)
			(thermal_gap 0.1651)
		)
		(pad "C13" thru_hole circle
			(at 28.800044 -3.599942 180)
			(size 0.762 0.762)
			(drill 0.359918)
			(layers "*.Cu" "*.Mask")
			(remove_unused_layers no)
			(net "COMP_POWER_FAIL_N")
			(clearance 0.1651)
			(thermal_gap 0.1651)
		)
		(pad "C14" thru_hole circle
			(at 30.599888 -2.400046 180)
			(size 0.762 0.762)
			(drill 0.359918)
			(layers "*.Cu" "*.Mask")
			(remove_unused_layers no)
			(net "Net_86")
			(clearance 0.1651)
			(thermal_gap 0.1651)
		)
		(pad "C15" thru_hole circle
			(at 32.399986 -3.599942 180)
			(size 0.762 0.762)
			(drill 0.359918)
			(layers "*.Cu" "*.Mask")
			(remove_unused_layers no)
			(net "Net_212")
			(clearance 0.1651)
			(thermal_gap 0.1651)
		)
		(pad "C16" thru_hole circle
			(at 34.200084 -2.400046 180)
			(size 0.762 0.762)
			(drill 0.359918)
			(layers "*.Cu" "*.Mask")
			(remove_unused_layers no)
			(net "PWM_OUT_ZONE_C")
			(clearance 0.1651)
			(thermal_gap 0.1651)
		)
		(pad "D1" thru_hole circle
			(at 0 -4.99999 180)
			(size 0.762 0.762)
			(drill 0.359918)
			(layers "*.Cu" "*.Mask")
			(remove_unused_layers no)
			(net "PCIE_COMP_TO_IOM_RST_2")
			(clearance 0.1651)
			(thermal_gap 0.1651)
		)
		(pad "D2" thru_hole circle
			(at 1.800098 -3.800094 180)
			(size 0.762 0.762)
			(drill 0.359918)
			(layers "*.Cu" "*.Mask")
			(remove_unused_layers no)
			(net "I2C_SCC_SCL")
			(clearance 0.1651)
			(thermal_gap 0.1651)
		)
		(pad "D3" thru_hole circle
			(at 3.599942 -4.99999 180)
			(size 0.762 0.762)
			(drill 0.359918)
			(layers "*.Cu" "*.Mask")
			(remove_unused_layers no)
			(net "SCC_LOC_HEARTBEAT")
			(clearance 0.1651)
			(thermal_gap 0.1651)
		)
		(pad "D4" thru_hole circle
			(at 5.40004 -3.800094 180)
			(size 0.762 0.762)
			(drill 0.359918)
			(layers "*.Cu" "*.Mask")
			(remove_unused_layers no)
			(net "SCC_STBY_PWR_EN")
			(clearance 0.1651)
			(thermal_gap 0.1651)
		)
		(pad "D5" thru_hole circle
			(at 7.199884 -4.99999 180)
			(size 0.762 0.762)
			(drill 0.359918)
			(layers "*.Cu" "*.Mask")
			(remove_unused_layers no)
			(net "PCIE_COMP_TO_IOM_RST_3")
			(clearance 0.1651)
			(thermal_gap 0.1651)
		)
		(pad "D6" thru_hole circle
			(at 8.999982 -3.800094 180)
			(size 0.762 0.762)
			(drill 0.359918)
			(layers "*.Cu" "*.Mask")
			(remove_unused_layers no)
			(net "I2C_EXP_RMT_SCL")
			(clearance 0.1651)
			(thermal_gap 0.1651)
		)
		(pad "D7" thru_hole circle
			(at 10.80008 -4.99999 180)
			(size 0.762 0.762)
			(drill 0.359918)
			(layers "*.Cu" "*.Mask")
			(remove_unused_layers no)
			(net "UART_SDB_TX")
			(clearance 0.1651)
			(thermal_gap 0.1651)
		)
		(pad "D8" thru_hole circle
			(at 12.599924 -3.800094 180)
			(size 0.762 0.762)
			(drill 0.359918)
			(layers "*.Cu" "*.Mask")
			(remove_unused_layers no)
			(net "P12V_IOM")
			(clearance 0.1651)
			(thermal_gap 0.1651)
		)
		(pad "D9" thru_hole circle
			(at 21.599906 -4.99999 180)
			(size 0.762 0.762)
			(drill 0.359918)
			(layers "*.Cu" "*.Mask")
			(remove_unused_layers no)
			(net "PCIE_COMP_TO_IOM_RST_4")
			(clearance 0.1651)
			(thermal_gap 0.1651)
		)
		(pad "D10" thru_hole circle
			(at 23.400004 -3.800094 180)
			(size 0.762 0.762)
			(drill 0.359918)
			(layers "*.Cu" "*.Mask")
			(remove_unused_layers no)
			(net "I2C_BMC_COMP_SCL")
			(clearance 0.1651)
			(thermal_gap 0.1651)
		)
		(pad "D11" thru_hole circle
			(at 25.200102 -4.99999 180)
			(size 0.762 0.762)
			(drill 0.359918)
			(layers "*.Cu" "*.Mask")
			(remove_unused_layers no)
			(net "UART_COMP_TX")
			(clearance 0.1651)
			(thermal_gap 0.1651)
		)
		(pad "D12" thru_hole circle
			(at 26.999946 -3.800094 180)
			(size 0.762 0.762)
			(drill 0.359918)
			(layers "*.Cu" "*.Mask")
			(remove_unused_layers no)
			(net "SCC_RMT_TYPE_0")
			(clearance 0.1651)
			(thermal_gap 0.1651)
		)
		(pad "D13" thru_hole circle
			(at 28.800044 -4.99999 180)
			(size 0.762 0.762)
			(drill 0.359918)
			(layers "*.Cu" "*.Mask")
			(remove_unused_layers no)
			(net "COMP_FAST_THROTTLE_N")
			(clearance 0.1651)
			(thermal_gap 0.1651)
		)
		(pad "D14" thru_hole circle
			(at 30.599888 -3.800094 180)
			(size 0.762 0.762)
			(drill 0.359918)
			(layers "*.Cu" "*.Mask")
			(remove_unused_layers no)
			(net "COMP_PWR_BTN_N")
			(clearance 0.1651)
			(thermal_gap 0.1651)
		)
		(pad "D15" thru_hole circle
			(at 32.399986 -4.99999 180)
			(size 0.762 0.762)
			(drill 0.359918)
			(layers "*.Cu" "*.Mask")
			(remove_unused_layers no)
			(net "ENCL_FAULT_LED")
			(clearance 0.1651)
			(thermal_gap 0.1651)
		)
		(pad "D16" thru_hole circle
			(at 34.200084 -3.800094 180)
			(size 0.762 0.762)
			(drill 0.359918)
			(layers "*.Cu" "*.Mask")
			(remove_unused_layers no)
			(net "PWM_OUT_ZONE_D")
			(clearance 0.1651)
			(thermal_gap 0.1651)
		)
		(pad "E1" thru_hole circle
			(at 0 -7.199884 180)
			(size 0.762 0.762)
			(drill 0.359918)
			(layers "*.Cu" "*.Mask")
			(remove_unused_layers no)
			(net "PCIE_IOM_TO_COMP_8_DN")
			(clearance 0.1651)
			(thermal_gap 0.1651)
		)
		(pad "E2" thru_hole circle
			(at 1.800098 -5.999988 180)
			(size 0.762 0.762)
			(drill 0.359918)
			(layers "*.Cu" "*.Mask")
			(remove_unused_layers no)
			(net "PCIE_IOM_TO_COMP_9_DN")
			(clearance 0.1651)
			(thermal_gap 0.1651)
		)
		(pad "E3" thru_hole circle
			(at 3.599942 -7.199884 180)
			(size 0.762 0.762)
			(drill 0.359918)
			(layers "*.Cu" "*.Mask")
			(remove_unused_layers no)
			(net "PCIE_IOM_TO_COMP_10_DN")
			(clearance 0.1651)
			(thermal_gap 0.1651)
		)
		(pad "E4" thru_hole circle
			(at 5.40004 -5.999988 180)
			(size 0.762 0.762)
			(drill 0.359918)
			(layers "*.Cu" "*.Mask")
			(remove_unused_layers no)
			(net "PCIE_IOM_TO_COMP_11_DN")
			(clearance 0.1651)
			(thermal_gap 0.1651)
		)
		(pad "E5" thru_hole circle
			(at 7.199884 -7.199884 180)
			(size 0.762 0.762)
			(drill 0.359918)
			(layers "*.Cu" "*.Mask")
			(remove_unused_layers no)
			(net "PCIE_IOM_TO_COMP_12_DN")
			(clearance 0.1651)
			(thermal_gap 0.1651)
		)
		(pad "E6" thru_hole circle
			(at 8.999982 -5.999988 180)
			(size 0.762 0.762)
			(drill 0.359918)
			(layers "*.Cu" "*.Mask")
			(remove_unused_layers no)
			(net "PCIE_IOM_TO_COMP_13_DN")
			(clearance 0.1651)
			(thermal_gap 0.1651)
		)
		(pad "E7" thru_hole circle
			(at 10.80008 -7.199884 180)
			(size 0.762 0.762)
			(drill 0.359918)
			(layers "*.Cu" "*.Mask")
			(remove_unused_layers no)
			(net "PCIE_IOM_TO_COMP_14_DN")
			(clearance 0.1651)
			(thermal_gap 0.1651)
		)
		(pad "E8" thru_hole circle
			(at 12.599924 -5.999988 180)
			(size 0.762 0.762)
			(drill 0.359918)
			(layers "*.Cu" "*.Mask")
			(remove_unused_layers no)
			(net "PCIE_IOM_TO_COMP_15_DN")
			(clearance 0.1651)
			(thermal_gap 0.1651)
		)
	)
)
